(kicad_pcb
	(version 20260206)
	(generator "pcbnew")
	(generator_version "10.0")
	(general
		(thickness 1.6)
		(legacy_teardrops no)
	)
	(paper "A4")
	(title_block
		(title "04192023_DAF0TMB3IC0_F0TG_MB_C_brd_V02_OCP.brd")
		(comment 1 "Grand Teton / footprints 3421-3424 of 8354")
	)
	(layers
		(0 "F.Cu" signal "TOP")
		(4 "In1.Cu" signal "GND")
		(6 "In2.Cu" signal "IN1")
		(8 "In3.Cu" signal "GND1")
		(10 "In4.Cu" signal "IN2")
		(12 "In5.Cu" signal "GND2")
		(14 "In6.Cu" signal "IN3")
		(16 "In7.Cu" signal "GND3")
		(18 "In8.Cu" signal "VCC")
		(20 "In9.Cu" signal "VCC1")
		(22 "In10.Cu" signal "GND4")
		(24 "In11.Cu" signal "IN4")
		(26 "In12.Cu" signal "GND5")
		(28 "In13.Cu" signal "IN5")
		(30 "In14.Cu" signal "GND6")
		(32 "In15.Cu" signal "IN6")
		(34 "In16.Cu" signal "GND7")
		(2 "B.Cu" signal "BOTTOM")
		(9 "F.Adhes" user "F.Adhesive")
		(11 "B.Adhes" user "B.Adhesive")
		(13 "F.Paste" user "Package Geometry/Pastemask Top")
		(15 "B.Paste" user "Package Geometry/Pastemask Bottom")
		(5 "F.SilkS" user "Ref Des/Silkscreen Top")
		(7 "B.SilkS" user "Ref Des/Silkscreen Bottom")
		(1 "F.Mask" user "Board Geometry/Soldermask Top")
		(3 "B.Mask" user "Board Geometry/Soldermask Bottom")
		(17 "Dwgs.User" user "User.Drawings")
		(19 "Cmts.User" user "User.Comments")
		(21 "Eco1.User" user "User.Eco1")
		(23 "Eco2.User" user "User.Eco2")
		(25 "Edge.Cuts" user "Board Geometry/Outline")
		(27 "Margin" user)
		(31 "F.CrtYd" user "Package Geometry/Place Bound Top")
		(29 "B.CrtYd" user "Package Geometry/Place Bound Bottom")
		(35 "F.Fab" user "Ref Des/Assembly Top")
		(33 "B.Fab" user "Ref Des/Assembly Bottom")
	)
	(footprint ""
		(layer "F.Cu")
		(at 67.672458 -27.889962 -90)
		(property "Reference" "PU206"
			(at 4.33959 1.244346 0)
			(unlocked yes)
			(layer "F.SilkS")
			(effects
				(font
					(size 0.7874 0.5842)
					(thickness 0.1524)
				)
				(justify left)
			)
		)
		(property "Value" ""
			(at 0 0 270)
			(layer "F.Fab")
			(effects
				(font
					(size 1.27 1.27)
				)
			)
		)
		(duplicate_pad_numbers_are_jumpers no)
		(fp_line
			(start -1.549908 2.549906)
			(end -0.753872 2.549906)
			(stroke
				(width 0.1524)
				(type default)
			)
			(layer "F.SilkS")
		)
		(fp_line
			(start -0.245872 2.549906)
			(end 0.245872 2.549906)
			(stroke
				(width 0.1524)
				(type default)
			)
			(layer "F.SilkS")
		)
		(fp_line
			(start 0.753872 2.549906)
			(end 1.549908 2.549906)
			(stroke
				(width 0.1524)
				(type default)
			)
			(layer "F.SilkS")
		)
		(fp_line
			(start 1.549908 2.549906)
			(end 1.549908 2.253996)
			(stroke
				(width 0.1524)
				(type default)
			)
			(layer "F.SilkS")
		)
		(fp_line
			(start -1.549908 2.253996)
			(end -1.549908 2.549906)
			(stroke
				(width 0.1524)
				(type default)
			)
			(layer "F.SilkS")
		)
		(fp_line
			(start 1.549908 -2.253996)
			(end 1.549908 -2.549906)
			(stroke
				(width 0.1524)
				(type default)
			)
			(layer "F.SilkS")
		)
		(fp_line
			(start -1.549908 -2.549906)
			(end -1.549908 -2.251964)
			(stroke
				(width 0.1524)
				(type default)
			)
			(layer "F.SilkS")
		)
		(fp_line
			(start -0.752094 -2.549906)
			(end -1.549908 -2.549906)
			(stroke
				(width 0.1524)
				(type default)
			)
			(layer "F.SilkS")
		)
		(fp_line
			(start 0.2413 -2.549906)
			(end -0.2413 -2.549906)
			(stroke
				(width 0.1524)
				(type default)
			)
			(layer "F.SilkS")
		)
		(fp_line
			(start 1.549908 -2.549906)
			(end 0.752094 -2.549906)
			(stroke
				(width 0.1524)
				(type default)
			)
			(layer "F.SilkS")
		)
		(fp_poly
			(pts
				(xy -2.104644 -3.527298) (xy -1.927606 -2.591562) (xy -2.782062 -3.011424)
			)
			(stroke
				(width 0)
				(type default)
			)
			(fill yes)
			(layer "F.SilkS")
		)
		(fp_line
			(start -1.549908 2.549906)
			(end 1.549908 2.549906)
			(stroke
				(width 0.1)
				(type default)
			)
			(layer "F.Fab")
		)
		(fp_line
			(start 1.549908 2.549906)
			(end 1.549908 -2.549906)
			(stroke
				(width 0.1)
				(type default)
			)
			(layer "F.Fab")
		)
		(fp_line
			(start -1.549908 -2.549906)
			(end -1.549908 2.549906)
			(stroke
				(width 0.1)
				(type default)
			)
			(layer "F.Fab")
		)
		(fp_line
			(start 1.549908 -2.549906)
			(end -1.549908 -2.549906)
			(stroke
				(width 0.1)
				(type default)
			)
			(layer "F.Fab")
		)
		(fp_poly
			(pts
				(xy -1.891538 -1.999996) (xy -2.7432 -1.574292) (xy -2.7432 -2.4257)
			)
			(stroke
				(width 0)
				(type default)
			)
			(fill yes)
			(layer "F.Fab")
		)
		(fp_text user "11"
			(at 2.3368 5.107432 270)
			(unlocked yes)
			(layer "F.SilkS")
			(effects
				(font
					(size 0.635 0.4064)
					(thickness 0.1524)
				)
			)
		)
		(fp_text user "10"
			(at -1.9304 3.126232 270)
			(unlocked yes)
			(layer "F.SilkS")
			(effects
				(font
					(size 0.635 0.4064)
					(thickness 0.1524)
				)
			)
		)
		(fp_text user "9"
			(at -2.592832 2.2098 180)
			(unlocked yes)
			(layer "F.SilkS")
			(effects
				(font
					(size 0.635 0.4064)
					(thickness 0.1524)
				)
			)
		)
		(fp_text user "12"
			(at 2.461768 1.0668 180)
			(unlocked yes)
			(layer "F.SilkS")
			(effects
				(font
					(size 0.635 0.4064)
					(thickness 0.1524)
				)
			)
		)
		(fp_text user "21_22"
			(at -0.0762 -3.401568 270)
			(unlocked yes)
			(layer "F.SilkS")
			(effects
				(font
					(size 0.635 0.4064)
					(thickness 0.1524)
				)
			)
		)
		(fp_text user "20"
			(at 3.706368 -3.5306 180)
			(unlocked yes)
			(layer "F.SilkS")
			(effects
				(font
					(size 0.635 0.4064)
					(thickness 0.1524)
				)
			)
		)
		(fp_text user "11"
			(at 1.1938 3.329432 270)
			(unlocked yes)
			(layer "F.Fab")
			(effects
				(font
					(size 0.635 0.4064)
					(thickness 0.1524)
				)
			)
		)
		(fp_text user "10"
			(at -1.4224 3.253232 270)
			(unlocked yes)
			(layer "F.Fab")
			(effects
				(font
					(size 0.635 0.4064)
					(thickness 0.1524)
				)
			)
		)
		(fp_text user "12"
			(at 2.207768 2.7178 180)
			(unlocked yes)
			(layer "F.Fab")
			(effects
				(font
					(size 0.635 0.4064)
					(thickness 0.1524)
				)
			)
		)
		(fp_text user "9"
			(at -2.338832 2.5908 180)
			(unlocked yes)
			(layer "F.Fab")
			(effects
				(font
					(size 0.635 0.4064)
					(thickness 0.1524)
				)
			)
		)
		(fp_text user "20"
			(at 2.055368 -2.7686 180)
			(unlocked yes)
			(layer "F.Fab")
			(effects
				(font
					(size 0.635 0.4064)
					(thickness 0.1524)
				)
			)
		)
		(fp_text user "21_22"
			(at -0.0762 -3.401568 270)
			(unlocked yes)
			(layer "F.Fab")
			(effects
				(font
					(size 0.635 0.4064)
					(thickness 0.1524)
				)
			)
		)
		(pad "1" smd circle
			(at -1.374902 -1.999996 180)
			(size 0 0)
			(layers "F.Cu" "F.Mask" "F.Paste")
			(net "P12V_OCP_V3_2_EN_2_R3")
		)
		(pad "2" smd rect
			(at -1.400048 -1.500124 180)
			(size 0.254 0.8128)
			(layers "F.Cu" "F.Mask" "F.Paste")
			(net "GND")
		)
		(pad "3" smd rect
			(at -1.400048 -0.999998 180)
			(size 0.254 0.8128)
			(layers "F.Cu" "F.Mask" "F.Paste")
			(net "GND")
		)
		(pad "4" smd rect
			(at -1.400048 -0.499872 180)
			(size 0.254 0.8128)
			(layers "F.Cu" "F.Mask" "F.Paste")
			(net "P12V_OCP_TIMER_2")
		)
		(pad "5" smd rect
			(at -1.400048 0 180)
			(size 0.254 0.8128)
			(layers "F.Cu" "F.Mask" "F.Paste")
			(net "P12V_OCP_ISET_2")
		)
		(pad "6" smd rect
			(at -1.400048 0.499872 180)
			(size 0.254 0.8128)
			(layers "F.Cu" "F.Mask" "F.Paste")
			(net "P12V_OCP_SS_2")
		)
		(pad "7" smd rect
			(at -1.400048 0.999998 180)
			(size 0.254 0.8128)
			(layers "F.Cu" "F.Mask" "F.Paste")
			(net "GND")
		)
		(pad "8" smd rect
			(at -1.400048 1.500124 180)
			(size 0.254 0.8128)
			(layers "F.Cu" "F.Mask" "F.Paste")
			(net "P12V_OCP_IMON_2")
		)
		(pad "9" smd rect
			(at -1.400048 1.999996 180)
			(size 0.254 0.8128)
			(layers "F.Cu" "F.Mask" "F.Paste")
			(net "P12V_OCP_FLTB_2")
		)
		(pad "10" smd rect
			(at -0.499872 2.400046 270)
			(size 0.254 0.8128)
			(layers "F.Cu" "F.Mask" "F.Paste")
			(net "HP_LVC3_OCP_V3_2_P12V_PWRGD")
		)
		(pad "11" smd rect
			(at 0.499872 2.400046 270)
			(size 0.254 0.8128)
			(layers "F.Cu" "F.Mask" "F.Paste")
			(net "P12V_OCP_OV_FB_2")
		)
		(pad "12" smd rect
			(at 1.400048 1.999996 180)
			(size 0.254 0.8128)
			(layers "F.Cu" "F.Mask" "F.Paste")
			(net "P12V_OCP_AVIN_PD_2")
		)
		(pad "13" smd rect
			(at 1.400048 1.500124 180)
			(size 0.254 0.8128)
			(layers "F.Cu" "F.Mask" "F.Paste")
			(net "P12V_OCP_V3_2")
		)
		(pad "14" smd rect
			(at 1.400048 0.999998 180)
			(size 0.254 0.8128)
			(layers "F.Cu" "F.Mask" "F.Paste")
			(net "P12V_OCP_V3_2")
		)
		(pad "15" smd rect
			(at 1.400048 0.499872 180)
			(size 0.254 0.8128)
			(layers "F.Cu" "F.Mask" "F.Paste")
			(net "P12V_OCP_V3_2")
		)
		(pad "16" smd rect
			(at 1.400048 0 180)
			(size 0.254 0.8128)
			(layers "F.Cu" "F.Mask" "F.Paste")
			(net "P12V_OCP_V3_2")
		)
		(pad "17" smd rect
			(at 1.400048 -0.499872 180)
			(size 0.254 0.8128)
			(layers "F.Cu" "F.Mask" "F.Paste")
			(net "P12V_OCP_V3_2")
		)
		(pad "18" smd rect
			(at 1.400048 -0.999998 180)
			(size 0.254 0.8128)
			(layers "F.Cu" "F.Mask" "F.Paste")
			(net "P12V_OCP_V3_2")
		)
		(pad "19" smd rect
			(at 1.400048 -1.500124 180)
			(size 0.254 0.8128)
			(layers "F.Cu" "F.Mask" "F.Paste")
			(net "P12V_OCP_V3_2")
		)
		(pad "20" smd rect
			(at 1.400048 -1.999996 180)
			(size 0.254 0.8128)
			(layers "F.Cu" "F.Mask" "F.Paste")
			(net "P12V_OCP_V3_2")
		)
		(pad "21_22" smd circle
			(at 0.499872 -2.337562 180)
			(size 0 0)
			(layers "F.Cu" "F.Mask" "F.Paste")
			(net "P12V_AUX")
		)
		(pad "23" smd rect
			(at 0 -1.100074 180)
			(size 0.254 1.27)
			(layers "F.Cu" "F.Mask" "F.Paste")
			(net "P12V_AUX")
		)
		(pad "24" smd rect
			(at 0 -0.199898 180)
			(size 0.254 1.27)
			(layers "F.Cu" "F.Mask" "F.Paste")
			(net "P12V_AUX")
		)
		(pad "25" smd rect
			(at 0 0.700024 180)
			(size 0.254 1.27)
			(layers "F.Cu" "F.Mask" "F.Paste")
			(net "P12V_AUX")
		)
		(pad "26" smd rect
			(at 0 1.599946 180)
			(size 0.254 1.27)
			(layers "F.Cu" "F.Mask" "F.Paste")
			(net "P12V_AUX")
		)
	)
	(footprint ""
		(layer "F.Cu")
		(at 197.177406 -40.138604)
		(property "Reference" "R3996"
			(at 0 0 0)
			(layer "F.SilkS")
			(hide yes)
			(effects
				(font
					(size 1.27 1.27)
				)
			)
		)
		(property "Value" ""
			(at 0 0 0)
			(layer "F.Fab")
			(effects
				(font
					(size 1.27 1.27)
				)
			)
		)
		(duplicate_pad_numbers_are_jumpers no)
		(fp_line
			(start -0.7874 -0.4064)
			(end 0.7874 -0.4064)
			(stroke
				(width 0.1524)
				(type default)
			)
			(layer "F.SilkS")
		)
		(fp_line
			(start -0.7874 0.4064)
			(end -0.7874 -0.4064)
			(stroke
				(width 0.1524)
				(type default)
			)
			(layer "F.SilkS")
		)
		(fp_line
			(start 0.7874 -0.4064)
			(end 0.7874 0.4064)
			(stroke
				(width 0.1524)
				(type default)
			)
			(layer "F.SilkS")
		)
		(fp_line
			(start 0.7874 0.4064)
			(end -0.7874 0.4064)
			(stroke
				(width 0.1524)
				(type default)
			)
			(layer "F.SilkS")
		)
		(fp_line
			(start -0.67945 -0.305054)
			(end -0.12065 -0.305054)
			(stroke
				(width 0.1)
				(type default)
			)
			(layer "F.Fab")
		)
		(fp_line
			(start -0.67945 0.3048)
			(end -0.67945 -0.305054)
			(stroke
				(width 0.1)
				(type default)
			)
			(layer "F.Fab")
		)
		(fp_line
			(start -0.12065 -0.305054)
			(end -0.12065 -0.2794)
			(stroke
				(width 0.1)
				(type default)
			)
			(layer "F.Fab")
		)
		(fp_line
			(start -0.12065 -0.2794)
			(end 0.12065 -0.2794)
			(stroke
				(width 0.1)
				(type default)
			)
			(layer "F.Fab")
		)
		(fp_line
			(start -0.12065 0.2794)
			(end -0.12065 0.3048)
			(stroke
				(width 0.1)
				(type default)
			)
			(layer "F.Fab")
		)
		(fp_line
			(start -0.12065 0.3048)
			(end -0.67945 0.3048)
			(stroke
				(width 0.1)
				(type default)
			)
			(layer "F.Fab")
		)
		(fp_line
			(start 0.120396 0.2794)
			(end -0.12065 0.2794)
			(stroke
				(width 0.1)
				(type default)
			)
			(layer "F.Fab")
		)
		(fp_line
			(start 0.120396 0.3048)
			(end 0.120396 0.2794)
			(stroke
				(width 0.1)
				(type default)
			)
			(layer "F.Fab")
		)
		(fp_line
			(start 0.12065 -0.3048)
			(end 0.67945 -0.3048)
			(stroke
				(width 0.1)
				(type default)
			)
			(layer "F.Fab")
		)
		(fp_line
			(start 0.12065 -0.2794)
			(end 0.12065 -0.3048)
			(stroke
				(width 0.1)
				(type default)
			)
			(layer "F.Fab")
		)
		(fp_line
			(start 0.67945 -0.3048)
			(end 0.67945 0.3048)
			(stroke
				(width 0.1)
				(type default)
			)
			(layer "F.Fab")
		)
		(fp_line
			(start 0.67945 0.3048)
			(end 0.120396 0.3048)
			(stroke
				(width 0.1)
				(type default)
			)
			(layer "F.Fab")
		)
		(pad "1" smd circle
			(at -0.40005 0)
			(size 0 0)
			(layers "F.Cu" "F.Mask" "F.Paste")
			(net "VIRTUAL_RESEAT_FPGA_N")
		)
		(pad "2" smd circle
			(at 0.40005 0)
			(size 0 0)
			(layers "F.Cu" "F.Mask" "F.Paste")
			(net "P12V_SCM_EN")
		)
	)
	(footprint ""
		(layer "F.Cu")
		(at 398.437862 -416.899344 -90)
		(property "Reference" "C6584"
			(at 0 0 270)
			(layer "F.SilkS")
			(hide yes)
			(effects
				(font
					(size 1.27 1.27)
				)
			)
		)
		(property "Value" ""
			(at 0 0 270)
			(layer "F.Fab")
			(effects
				(font
					(size 1.27 1.27)
				)
			)
		)
		(duplicate_pad_numbers_are_jumpers no)
		(fp_line
			(start -0.299974 0.150114)
			(end -0.299974 -0.150114)
			(stroke
				(width 0.1)
				(type default)
			)
			(layer "F.Fab")
		)
		(fp_line
			(start 0.299974 0.150114)
			(end -0.299974 0.150114)
			(stroke
				(width 0.1)
				(type default)
			)
			(layer "F.Fab")
		)
		(fp_line
			(start -0.299974 -0.150114)
			(end 0.299974 -0.150114)
			(stroke
				(width 0.1)
				(type default)
			)
			(layer "F.Fab")
		)
		(fp_line
			(start 0.299974 -0.150114)
			(end 0.299974 0.150114)
			(stroke
				(width 0.1)
				(type default)
			)
			(layer "F.Fab")
		)
		(pad "1" smd rect
			(at -0.2667 0 270)
			(size 0.3048 0.381)
			(layers "F.Cu" "F.Mask" "F.Paste")
			(net "P5E_CPU0_P2_TX_BUF_C_DN<9>")
		)
		(pad "2" smd rect
			(at 0.2667 0 270)
			(size 0.3048 0.381)
			(layers "F.Cu" "F.Mask" "F.Paste")
			(net "P5E_CPU0_P2_TX_BUF_DN<9>")
		)
	)
	(footprint ""
		(layer "F.Cu")
		(at 127.659892 -168.196768)
		(property "Reference" "PC149"
			(at 0 0 0)
			(layer "F.SilkS")
			(hide yes)
			(effects
				(font
					(size 1.27 1.27)
				)
			)
		)
		(property "Value" ""
			(at 0 0 0)
			(layer "F.Fab")
			(effects
				(font
					(size 1.27 1.27)
				)
			)
		)
		(duplicate_pad_numbers_are_jumpers no)
		(fp_line
			(start -0.7874 -0.4064)
			(end 0.7874 -0.4064)
			(stroke
				(width 0.1524)
				(type default)
			)
			(layer "F.SilkS")
		)
		(fp_line
			(start -0.7874 0.4064)
			(end -0.7874 -0.4064)
			(stroke
				(width 0.1524)
				(type default)
			)
			(layer "F.SilkS")
		)
		(fp_line
			(start 0.7874 -0.4064)
			(end 0.7874 0.4064)
			(stroke
				(width 0.1524)
				(type default)
			)
			(layer "F.SilkS")
		)
		(fp_line
			(start 0.7874 0.4064)
			(end -0.7874 0.4064)
			(stroke
				(width 0.1524)
				(type default)
			)
			(layer "F.SilkS")
		)
		(fp_line
			(start -0.67945 -0.305054)
			(end -0.12065 -0.305054)
			(stroke
				(width 0.1)
				(type default)
			)
			(layer "F.Fab")
		)
		(fp_line
			(start -0.67945 0.3048)
			(end -0.67945 -0.305054)
			(stroke
				(width 0.1)
				(type default)
			)
			(layer "F.Fab")
		)
		(fp_line
			(start -0.12065 -0.305054)
			(end -0.12065 -0.2794)
			(stroke
				(width 0.1)
				(type default)
			)
			(layer "F.Fab")
		)
		(fp_line
			(start -0.12065 -0.2794)
			(end 0.12065 -0.2794)
			(stroke
				(width 0.1)
				(type default)
			)
			(layer "F.Fab")
		)
		(fp_line
			(start -0.12065 0.2794)
			(end -0.12065 0.3048)
			(stroke
				(width 0.1)
				(type default)
			)
			(layer "F.Fab")
		)
		(fp_line
			(start -0.12065 0.3048)
			(end -0.67945 0.3048)
			(stroke
				(width 0.1)
				(type default)
			)
			(layer "F.Fab")
		)
		(fp_line
			(start 0.120396 0.2794)
			(end -0.12065 0.2794)
			(stroke
				(width 0.1)
				(type default)
			)
			(layer "F.Fab")
		)
		(fp_line
			(start 0.120396 0.3048)
			(end 0.120396 0.2794)
			(stroke
				(width 0.1)
				(type default)
			)
			(layer "F.Fab")
		)
		(fp_line
			(start 0.12065 -0.3048)
			(end 0.67945 -0.3048)
			(stroke
				(width 0.1)
				(type default)
			)
			(layer "F.Fab")
		)
		(fp_line
			(start 0.12065 -0.2794)
			(end 0.12065 -0.3048)
			(stroke
				(width 0.1)
				(type default)
			)
			(layer "F.Fab")
		)
		(fp_line
			(start 0.67945 -0.3048)
			(end 0.67945 0.3048)
			(stroke
				(width 0.1)
				(type default)
			)
			(layer "F.Fab")
		)
		(fp_line
			(start 0.67945 0.3048)
			(end 0.120396 0.3048)
			(stroke
				(width 0.1)
				(type default)
			)
			(layer "F.Fab")
		)
		(pad "1" smd circle
			(at -0.40005 0)
			(size 0 0)
			(layers "F.Cu" "F.Mask" "F.Paste")
			(net "SW_PVDDCR_SOC_P1_SW2")
		)
		(pad "2" smd circle
			(at 0.40005 0)
			(size 0 0)
			(layers "F.Cu" "F.Mask" "F.Paste")
			(net "SW_PVDDCR_SOC_P1_SW2_RC")
		)
	)
)
